# S9S_MB_2U (Grand Teton) — schematic netlist excerpt (pin names and nets, part order shuffled) for the footprints in the layout excerpt that follows; sources: Cadence DE-HDL packaged netlist, KiCad conversion of 03242023_DA0F0TMBIJ0_F0T_Motherboard_J_brd_V01_OCP.brd

R3638  Q_RES  10K 1% CHIP  pkg 0402LF  page 208 : A = P3V3_AUX ; B = CK440Q_OE_1
R1324  Q_RES  1K 1% CHIP  pkg 0402LF  page 201 : A = GND ; B = PD_BIOS_IMAGE_SWAP_N

(kicad_pcb
	(version 20260206)
	(generator "pcbnew")
	(generator_version "10.0")
	(general
		(thickness 1.6)
		(legacy_teardrops no)
	)
	(paper "A4")
	(title_block
		(title "03242023_DA0F0TMBIJ0_F0T_Motherboard_J_brd_V01_OCP.brd")
		(comment 1 "Grand Teton / footprints 253-254 of 6105")
	)
	(layers
		(0 "F.Cu" signal "TOP")
		(4 "In1.Cu" signal "GND")
		(6 "In2.Cu" signal "IN1")
		(8 "In3.Cu" signal "GND1")
		(10 "In4.Cu" signal "IN2")
		(12 "In5.Cu" signal "GND2")
		(14 "In6.Cu" signal "IN3")
		(16 "In7.Cu" signal "GND3")
		(18 "In8.Cu" signal "VCC")
		(20 "In9.Cu" signal "VCC1")
		(22 "In10.Cu" signal "GND4")
		(24 "In11.Cu" signal "IN4")
		(26 "In12.Cu" signal "GND5")
		(28 "In13.Cu" signal "IN5")
		(30 "In14.Cu" signal "GND6")
		(32 "In15.Cu" signal "IN6")
		(34 "In16.Cu" signal "GND7")
		(2 "B.Cu" signal "BOTTOM")
		(9 "F.Adhes" user "F.Adhesive")
		(11 "B.Adhes" user "B.Adhesive")
		(13 "F.Paste" user "Package Geometry/Pastemask Top")
		(15 "B.Paste" user "Package Geometry/Pastemask Bottom")
		(5 "F.SilkS" user "Ref Des/Silkscreen Top")
		(7 "B.SilkS" user "Ref Des/Silkscreen Bottom")
		(1 "F.Mask" user "Board Geometry/Soldermask Top")
		(3 "B.Mask" user "Board Geometry/Soldermask Bottom")
		(17 "Dwgs.User" user "User.Drawings")
		(19 "Cmts.User" user "User.Comments")
		(21 "Eco1.User" user "User.Eco1")
		(23 "Eco2.User" user "User.Eco2")
		(25 "Edge.Cuts" user "Board Geometry/Outline")
		(27 "Margin" user)
		(31 "F.CrtYd" user "Package Geometry/Place Bound Top")
		(29 "B.CrtYd" user "Package Geometry/Place Bound Bottom")
		(35 "F.Fab" user "Ref Des/Assembly Top")
		(33 "B.Fab" user "Ref Des/Assembly Bottom")
	)
	(footprint ""
		(layer "F.Cu")
		(at 261.600188 -92.498926 90)
		(property "Reference" "R3638"
			(at 0 0 90)
			(layer "F.SilkS")
			(hide yes)
			(effects
				(font
					(size 1.27 1.27)
				)
			)
		)
		(property "Value" ""
			(at 0 0 90)
			(layer "F.Fab")
			(effects
				(font
					(size 1.27 1.27)
				)
			)
		)
		(duplicate_pad_numbers_are_jumpers no)
		(fp_line
			(start 0.7874 -0.4064)
			(end 0.7874 0.4064)
			(stroke
				(width 0.1524)
				(type default)
			)
			(layer "F.SilkS")
		)
		(fp_line
			(start -0.7874 -0.4064)
			(end 0.7874 -0.4064)
			(stroke
				(width 0.1524)
				(type default)
			)
			(layer "F.SilkS")
		)
		(fp_line
			(start 0.7874 0.4064)
			(end -0.7874 0.4064)
			(stroke
				(width 0.1524)
				(type default)
			)
			(layer "F.SilkS")
		)
		(fp_line
			(start -0.7874 0.4064)
			(end -0.7874 -0.4064)
			(stroke
				(width 0.1524)
				(type default)
			)
			(layer "F.SilkS")
		)
		(fp_line
			(start -0.12065 -0.305054)
			(end -0.12065 -0.2794)
			(stroke
				(width 0.1)
				(type default)
			)
			(layer "F.Fab")
		)
		(fp_line
			(start -0.67945 -0.305054)
			(end -0.12065 -0.305054)
			(stroke
				(width 0.1)
				(type default)
			)
			(layer "F.Fab")
		)
		(fp_line
			(start 0.67945 -0.3048)
			(end 0.67945 0.3048)
			(stroke
				(width 0.1)
				(type default)
			)
			(layer "F.Fab")
		)
		(fp_line
			(start 0.12065 -0.3048)
			(end 0.67945 -0.3048)
			(stroke
				(width 0.1)
				(type default)
			)
			(layer "F.Fab")
		)
		(fp_line
			(start 0.12065 -0.2794)
			(end 0.12065 -0.3048)
			(stroke
				(width 0.1)
				(type default)
			)
			(layer "F.Fab")
		)
		(fp_line
			(start -0.12065 -0.2794)
			(end 0.12065 -0.2794)
			(stroke
				(width 0.1)
				(type default)
			)
			(layer "F.Fab")
		)
		(fp_line
			(start 0.120396 0.2794)
			(end -0.12065 0.2794)
			(stroke
				(width 0.1)
				(type default)
			)
			(layer "F.Fab")
		)
		(fp_line
			(start -0.12065 0.2794)
			(end -0.12065 0.3048)
			(stroke
				(width 0.1)
				(type default)
			)
			(layer "F.Fab")
		)
		(fp_line
			(start 0.67945 0.3048)
			(end 0.120396 0.3048)
			(stroke
				(width 0.1)
				(type default)
			)
			(layer "F.Fab")
		)
		(fp_line
			(start 0.120396 0.3048)
			(end 0.120396 0.2794)
			(stroke
				(width 0.1)
				(type default)
			)
			(layer "F.Fab")
		)
		(fp_line
			(start -0.12065 0.3048)
			(end -0.67945 0.3048)
			(stroke
				(width 0.1)
				(type default)
			)
			(layer "F.Fab")
		)
		(fp_line
			(start -0.67945 0.3048)
			(end -0.67945 -0.305054)
			(stroke
				(width 0.1)
				(type default)
			)
			(layer "F.Fab")
		)
		(pad "1" smd circle
			(at -0.40005 0 90)
			(size 0 0)
			(layers "F.Cu" "F.Mask" "F.Paste")
			(net "P3V3_AUX")
		)
		(pad "2" smd circle
			(at 0.40005 0 90)
			(size 0 0)
			(layers "F.Cu" "F.Mask" "F.Paste")
			(net "CK440Q_OE_1")
		)
	)
	(footprint ""
		(layer "F.Cu")
		(at 435.185566 -40.104568 180)
		(property "Reference" "R1324"
			(at 0 0 180)
			(layer "F.SilkS")
			(hide yes)
			(effects
				(font
					(size 1.27 1.27)
				)
			)
		)
		(property "Value" ""
			(at 0 0 180)
			(layer "F.Fab")
			(effects
				(font
					(size 1.27 1.27)
				)
			)
		)
		(duplicate_pad_numbers_are_jumpers no)
		(fp_line
			(start 0.7874 0.4064)
			(end -0.7874 0.4064)
			(stroke
				(width 0.1524)
				(type default)
			)
			(layer "F.SilkS")
		)
		(fp_line
			(start 0.7874 -0.4064)
			(end 0.7874 0.4064)
			(stroke
				(width 0.1524)
				(type default)
			)
			(layer "F.SilkS")
		)
		(fp_line
			(start -0.7874 0.4064)
			(end -0.7874 -0.4064)
			(stroke
				(width 0.1524)
				(type default)
			)
			(layer "F.SilkS")
		)
		(fp_line
			(start -0.7874 -0.4064)
			(end 0.7874 -0.4064)
			(stroke
				(width 0.1524)
				(type default)
			)
			(layer "F.SilkS")
		)
		(fp_line
			(start 0.67945 0.3048)
			(end 0.120396 0.3048)
			(stroke
				(width 0.1)
				(type default)
			)
			(layer "F.Fab")
		)
		(fp_line
			(start 0.67945 -0.3048)
			(end 0.67945 0.3048)
			(stroke
				(width 0.1)
				(type default)
			)
			(layer "F.Fab")
		)
		(fp_line
			(start 0.12065 -0.2794)
			(end 0.12065 -0.3048)
			(stroke
				(width 0.1)
				(type default)
			)
			(layer "F.Fab")
		)
		(fp_line
			(start 0.12065 -0.3048)
			(end 0.67945 -0.3048)
			(stroke
				(width 0.1)
				(type default)
			)
			(layer "F.Fab")
		)
		(fp_line
			(start 0.120396 0.3048)
			(end 0.120396 0.2794)
			(stroke
				(width 0.1)
				(type default)
			)
			(layer "F.Fab")
		)
		(fp_line
			(start 0.120396 0.2794)
			(end -0.12065 0.2794)
			(stroke
				(width 0.1)
				(type default)
			)
			(layer "F.Fab")
		)
		(fp_line
			(start -0.12065 0.3048)
			(end -0.67945 0.3048)
			(stroke
				(width 0.1)
				(type default)
			)
			(layer "F.Fab")
		)
		(fp_line
			(start -0.12065 0.2794)
			(end -0.12065 0.3048)
			(stroke
				(width 0.1)
				(type default)
			)
			(layer "F.Fab")
		)
		(fp_line
			(start -0.12065 -0.2794)
			(end 0.12065 -0.2794)
			(stroke
				(width 0.1)
				(type default)
			)
			(layer "F.Fab")
		)
		(fp_line
			(start -0.12065 -0.305054)
			(end -0.12065 -0.2794)
			(stroke
				(width 0.1)
				(type default)
			)
			(layer "F.Fab")
		)
		(fp_line
			(start -0.67945 0.3048)
			(end -0.67945 -0.305054)
			(stroke
				(width 0.1)
				(type default)
			)
			(layer "F.Fab")
		)
		(fp_line
			(start -0.67945 -0.305054)
			(end -0.12065 -0.305054)
			(stroke
				(width 0.1)
				(type default)
			)
			(layer "F.Fab")
		)
		(pad "1" smd circle
			(at -0.40005 0 180)
			(size 0 0)
			(layers "F.Cu" "F.Mask" "F.Paste")
			(net "GND")
		)
		(pad "2" smd circle
			(at 0.40005 0 180)
			(size 0 0)
			(layers "F.Cu" "F.Mask" "F.Paste")
			(net "PD_BIOS_IMAGE_SWAP_N")
		)
	)
)
